# S9S_MB_2U (Grand Teton) — schematic netlist excerpt (pin names and nets, part order shuffled) for the footprints in the layout excerpt that follows; sources: Cadence DE-HDL packaged netlist, KiCad conversion of 03242023_DA0F0TMBIJ0_F0T_Motherboard_J_brd_V01_OCP.brd

R1017  Q_RES  0 5% EMPTY  pkg 0402LF  page 209 : A = CLK_25M_PCH_CPU1_DP ; B = CLK_25M_NSSC_CPU1_DP
R4110  Q_RES  10K 1% CHIP  pkg 0402LF  page 184 : A = PD_PCH_GPP_E_14 ; B = GND

(kicad_pcb
	(version 20260206)
	(generator "pcbnew")
	(generator_version "10.0")
	(general
		(thickness 1.6)
		(legacy_teardrops no)
	)
	(paper "A4")
	(title_block
		(title "03242023_DA0F0TMBIJ0_F0T_Motherboard_J_brd_V01_OCP.brd")
		(comment 1 "Grand Teton / footprints 4352-4353 of 6105")
	)
	(layers
		(0 "F.Cu" signal "TOP")
		(4 "In1.Cu" signal "GND")
		(6 "In2.Cu" signal "IN1")
		(8 "In3.Cu" signal "GND1")
		(10 "In4.Cu" signal "IN2")
		(12 "In5.Cu" signal "GND2")
		(14 "In6.Cu" signal "IN3")
		(16 "In7.Cu" signal "GND3")
		(18 "In8.Cu" signal "VCC")
		(20 "In9.Cu" signal "VCC1")
		(22 "In10.Cu" signal "GND4")
		(24 "In11.Cu" signal "IN4")
		(26 "In12.Cu" signal "GND5")
		(28 "In13.Cu" signal "IN5")
		(30 "In14.Cu" signal "GND6")
		(32 "In15.Cu" signal "IN6")
		(34 "In16.Cu" signal "GND7")
		(2 "B.Cu" signal "BOTTOM")
		(9 "F.Adhes" user "F.Adhesive")
		(11 "B.Adhes" user "B.Adhesive")
		(13 "F.Paste" user "Package Geometry/Pastemask Top")
		(15 "B.Paste" user "Package Geometry/Pastemask Bottom")
		(5 "F.SilkS" user "Ref Des/Silkscreen Top")
		(7 "B.SilkS" user "Ref Des/Silkscreen Bottom")
		(1 "F.Mask" user "Board Geometry/Soldermask Top")
		(3 "B.Mask" user "Board Geometry/Soldermask Bottom")
		(17 "Dwgs.User" user "User.Drawings")
		(19 "Cmts.User" user "User.Comments")
		(21 "Eco1.User" user "User.Eco1")
		(23 "Eco2.User" user "User.Eco2")
		(25 "Edge.Cuts" user "Board Geometry/Outline")
		(27 "Margin" user)
		(31 "F.CrtYd" user "Package Geometry/Place Bound Top")
		(29 "B.CrtYd" user "Package Geometry/Place Bound Bottom")
		(35 "F.Fab" user "Ref Des/Assembly Top")
		(33 "B.Fab" user "Ref Des/Assembly Bottom")
	)
	(footprint ""
		(layer "B.Cu")
		(at 369.49888 -42.128948 180)
		(property "Reference" "R4110"
			(at 0 0 0)
			(layer "B.SilkS")
			(hide yes)
			(effects
				(font
					(size 1.27 1.27)
				)
				(justify mirror)
			)
		)
		(property "Value" ""
			(at 0 0 0)
			(layer "B.Fab")
			(effects
				(font
					(size 1.27 1.27)
				)
				(justify mirror)
			)
		)
		(duplicate_pad_numbers_are_jumpers no)
		(fp_line
			(start 0.7874 0.4064)
			(end 0.7874 -0.4064)
			(stroke
				(width 0.1524)
				(type default)
			)
			(layer "B.SilkS")
		)
		(fp_line
			(start 0.7874 -0.4064)
			(end -0.7874 -0.4064)
			(stroke
				(width 0.1524)
				(type default)
			)
			(layer "B.SilkS")
		)
		(fp_line
			(start -0.7874 0.4064)
			(end 0.7874 0.4064)
			(stroke
				(width 0.1524)
				(type default)
			)
			(layer "B.SilkS")
		)
		(fp_line
			(start -0.7874 -0.4064)
			(end -0.7874 0.4064)
			(stroke
				(width 0.1524)
				(type default)
			)
			(layer "B.SilkS")
		)
		(fp_line
			(start 0.67945 0.3048)
			(end 0.67945 -0.305054)
			(stroke
				(width 0.1)
				(type default)
			)
			(layer "B.Fab")
		)
		(fp_line
			(start 0.67945 -0.305054)
			(end 0.12065 -0.305054)
			(stroke
				(width 0.1)
				(type default)
			)
			(layer "B.Fab")
		)
		(fp_line
			(start 0.12065 0.3048)
			(end 0.67945 0.3048)
			(stroke
				(width 0.1)
				(type default)
			)
			(layer "B.Fab")
		)
		(fp_line
			(start 0.12065 0.2794)
			(end 0.12065 0.3048)
			(stroke
				(width 0.1)
				(type default)
			)
			(layer "B.Fab")
		)
		(fp_line
			(start 0.12065 -0.2794)
			(end -0.12065 -0.2794)
			(stroke
				(width 0.1)
				(type default)
			)
			(layer "B.Fab")
		)
		(fp_line
			(start 0.12065 -0.305054)
			(end 0.12065 -0.2794)
			(stroke
				(width 0.1)
				(type default)
			)
			(layer "B.Fab")
		)
		(fp_line
			(start -0.120396 0.3048)
			(end -0.120396 0.2794)
			(stroke
				(width 0.1)
				(type default)
			)
			(layer "B.Fab")
		)
		(fp_line
			(start -0.120396 0.2794)
			(end 0.12065 0.2794)
			(stroke
				(width 0.1)
				(type default)
			)
			(layer "B.Fab")
		)
		(fp_line
			(start -0.12065 -0.2794)
			(end -0.12065 -0.3048)
			(stroke
				(width 0.1)
				(type default)
			)
			(layer "B.Fab")
		)
		(fp_line
			(start -0.12065 -0.3048)
			(end -0.67945 -0.3048)
			(stroke
				(width 0.1)
				(type default)
			)
			(layer "B.Fab")
		)
		(fp_line
			(start -0.67945 0.3048)
			(end -0.120396 0.3048)
			(stroke
				(width 0.1)
				(type default)
			)
			(layer "B.Fab")
		)
		(fp_line
			(start -0.67945 -0.3048)
			(end -0.67945 0.3048)
			(stroke
				(width 0.1)
				(type default)
			)
			(layer "B.Fab")
		)
		(pad "1" smd circle
			(at 0.40005 0)
			(size 0 0)
			(layers "B.Cu" "B.Mask" "B.Paste")
			(net "PD_PCH_GPP_E_14")
		)
		(pad "2" smd circle
			(at -0.40005 0)
			(size 0 0)
			(layers "B.Cu" "B.Mask" "B.Paste")
			(net "GND")
		)
	)
	(footprint ""
		(layer "B.Cu")
		(at 236.982254 -134.048754)
		(property "Reference" "R1017"
			(at 0 0 0)
			(layer "B.SilkS")
			(hide yes)
			(effects
				(font
					(size 1.27 1.27)
				)
				(justify mirror)
			)
		)
		(property "Value" ""
			(at 0 0 0)
			(layer "B.Fab")
			(effects
				(font
					(size 1.27 1.27)
				)
				(justify mirror)
			)
		)
		(duplicate_pad_numbers_are_jumpers no)
		(fp_line
			(start -0.7874 -0.4064)
			(end -0.7874 0.4064)
			(stroke
				(width 0.1524)
				(type default)
			)
			(layer "B.SilkS")
		)
		(fp_line
			(start -0.7874 0.4064)
			(end 0.7874 0.4064)
			(stroke
				(width 0.1524)
				(type default)
			)
			(layer "B.SilkS")
		)
		(fp_line
			(start -0.559054 -0.4064)
			(end -0.7874 -0.4064)
			(stroke
				(width 0.1524)
				(type default)
			)
			(layer "B.SilkS")
		)
		(fp_line
			(start 0.7874 -0.4064)
			(end -0.223774 -0.4064)
			(stroke
				(width 0.1524)
				(type default)
			)
			(layer "B.SilkS")
		)
		(fp_line
			(start 0.7874 -0.226314)
			(end 0.7874 -0.4064)
			(stroke
				(width 0.1524)
				(type default)
			)
			(layer "B.SilkS")
		)
		(fp_line
			(start 0.7874 0.4064)
			(end 0.7874 0.253746)
			(stroke
				(width 0.1524)
				(type default)
			)
			(layer "B.SilkS")
		)
		(fp_line
			(start -0.67945 -0.3048)
			(end -0.67945 0.3048)
			(stroke
				(width 0.1)
				(type default)
			)
			(layer "B.Fab")
		)
		(fp_line
			(start -0.67945 0.3048)
			(end -0.120396 0.3048)
			(stroke
				(width 0.1)
				(type default)
			)
			(layer "B.Fab")
		)
		(fp_line
			(start -0.12065 -0.3048)
			(end -0.67945 -0.3048)
			(stroke
				(width 0.1)
				(type default)
			)
			(layer "B.Fab")
		)
		(fp_line
			(start -0.12065 -0.2794)
			(end -0.12065 -0.3048)
			(stroke
				(width 0.1)
				(type default)
			)
			(layer "B.Fab")
		)
		(fp_line
			(start -0.120396 0.2794)
			(end 0.12065 0.2794)
			(stroke
				(width 0.1)
				(type default)
			)
			(layer "B.Fab")
		)
		(fp_line
			(start -0.120396 0.3048)
			(end -0.120396 0.2794)
			(stroke
				(width 0.1)
				(type default)
			)
			(layer "B.Fab")
		)
		(fp_line
			(start 0.12065 -0.305054)
			(end 0.12065 -0.2794)
			(stroke
				(width 0.1)
				(type default)
			)
			(layer "B.Fab")
		)
		(fp_line
			(start 0.12065 -0.2794)
			(end -0.12065 -0.2794)
			(stroke
				(width 0.1)
				(type default)
			)
			(layer "B.Fab")
		)
		(fp_line
			(start 0.12065 0.2794)
			(end 0.12065 0.3048)
			(stroke
				(width 0.1)
				(type default)
			)
			(layer "B.Fab")
		)
		(fp_line
			(start 0.12065 0.3048)
			(end 0.67945 0.3048)
			(stroke
				(width 0.1)
				(type default)
			)
			(layer "B.Fab")
		)
		(fp_line
			(start 0.67945 -0.305054)
			(end 0.12065 -0.305054)
			(stroke
				(width 0.1)
				(type default)
			)
			(layer "B.Fab")
		)
		(fp_line
			(start 0.67945 0.3048)
			(end 0.67945 -0.305054)
			(stroke
				(width 0.1)
				(type default)
			)
			(layer "B.Fab")
		)
		(pad "1" smd rect
			(at 0.40005 0)
			(size 0.4572 0.508)
			(layers "B.Cu" "B.Mask" "B.Paste")
			(net "CLK_25M_PCH_CPU1_DP")
		)
		(pad "2" smd rect
			(at -0.40005 0)
			(size 0.4572 0.508)
			(layers "B.Cu" "B.Mask" "B.Paste")
			(net "CLK_25M_NSSC_CPU1_DP")
		)
	)
)
